# T6G (Grand Teton) — schematic parts with pin connectivity, parts 8082–8082 of 8303; source: Cadence DE-HDL packaged netlist (pstxprt.dat, pstxnet.dat, pstchip.dat)

U26  GENOA_SP5  SOCKET6096_13568-001 IO  pkg SOCKET6096_93-4X120-45XA  page 37  (pins 673-1008 of 6096)
  AJ44  G1_TXN5  OUT  = P5E_CPU1_G1_TX_DN<5>
  AJ45  VSS_AJ45  POWER  = GND
  AJ46  G1_TXP8  OUT  = P5E_CPU1_G1_TX_DP<8>
  AJ47  G1_TXN8  OUT  = P5E_CPU1_G1_TX_DN<8>
  AJ48  VSS_AJ48  POWER  = GND
  AJ49  G1_TXP11  OUT  = P5E_CPU1_G1_TX_DP<11>
  AJ50  G1_TXN11  OUT  = P5E_CPU1_G1_TX_DN<11>
  AJ51  VSS_AJ51  POWER  = GND
  AJ52  G1_TXP14  OUT  = P5E_CPU1_G1_TX_DP<14>
  AJ53  G1_TXN14  OUT  = P5E_CPU1_G1_TX_DN<14>
  AJ54  VSS_AJ54  POWER  = GND
  AJ55  MCA_DATA31  BI  = M_C_CPU1_SA_DQ<31>
  AJ56  VSS_AJ56  POWER  = GND
  AJ57  MCA_CHECK0  BI  = M_C_CPU1_SA_CB<0>
  AJ58  VDDIO_AJ58  POWER  = PVDDIO_P1
  AJ59  MDA_DATA31  BI  = M_D_CPU1_SA_DQ<31>
  AJ60  MDA_CHECK0  BI  = M_D_CPU1_SA_CB<0>
  AJ61  VSS_AJ61  POWER  = GND
  AJ62  MBA_DATA31  BI  = M_B_CPU1_SA_DQ<31>
  AJ63  VSS_AJ63  POWER  = GND
  AJ64  MBA_CHECK0  BI  = M_B_CPU1_SA_CB<0>
  AJ65  VDDIO_AJ65  POWER  = PVDDIO_P1
  AJ66  MFA_DATA31  BI  = M_F_CPU1_SA_DQ<31>
  AJ67  MFA_CHECK0  BI  = M_F_CPU1_SA_CB<0>
  AJ68  VSS_AJ68  POWER  = GND
  AJ69  MEA_DATA31  BI  = M_E_CPU1_SA_DQ<31>
  AJ70  VSS_AJ70  POWER  = GND
  AJ71  MEA_CHECK0  BI  = M_E_CPU1_SA_CB<0>
  AJ72  VDDIO_AJ72  POWER  = PVDDIO_P1
  AJ73  MAA_DATA31  BI  = M_A_CPU1_SA_DQ<31>
  AJ74  MAA_CHECK0  BI  = M_A_CPU1_SA_CB<0>
  AJ75  VSS_AJ75  POWER  = GND
  AK2  MGA_CHECK2  BI  = M_G_CPU1_SA_CB<2>
  AK3  VSS_AK3  POWER  = GND
  AK4  MGA_CHECK1  BI  = M_G_CPU1_SA_CB<1>
  AK5  VSS_AK5  POWER  = GND
  AK6  MKA_CHECK2  BI  = M_K_CPU1_SA_CB<2>
  AK7  MKA_CHECK1  BI  = M_K_CPU1_SA_CB<1>
  AK8  VSS_AK8  POWER  = GND
  AK9  MLA_CHECK2  BI  = M_L_CPU1_SA_CB<2>
  AK10  VSS_AK10  POWER  = GND
  AK11  MLA_CHECK1  BI  = M_L_CPU1_SA_CB<1>
  AK12  VSS_AK12  POWER  = GND
  AK13  MHA_CHECK2  BI  = M_H_CPU1_SA_CB<2>
  AK14  MHA_CHECK1  BI  = M_H_CPU1_SA_CB<1>
  AK15  VSS_AK15  POWER  = GND
  AK16  MJA_CHECK2  BI  = M_J_CPU1_SA_CB<2>
  AK17  VSS_AK17  POWER  = GND
  AK18  MJA_CHECK1  BI  = M_J_CPU1_SA_CB<1>
  AK19  VSS_AK19  POWER  = GND
  AK20  MIA_CHECK2  BI  = M_I_CPU1_SA_CB<2>
  AK21  MIA_CHECK1  BI  = M_I_CPU1_SA_CB<1>
  AK22  VSS_AK22  POWER  = GND
  AK23  VDDCR_CPU0_AK23  POWER  = PVDDCR_CPU0_P1
  AK24  VDDCR_CPU0_AK24  POWER  = PVDDCR_CPU0_P1
  AK25  VSS_AK25  POWER  = GND
  AK26  VDDCR_CPU0_AK26  POWER  = PVDDCR_CPU0_P1
  AK27  VDDCR_CPU0_AK27  POWER  = PVDDCR_CPU0_P1
  AK28  VSS_AK28  POWER  = GND
  AK29  VDDCR_CPU0_AK29  POWER  = PVDDCR_CPU0_P1
  AK30  VDDCR_CPU0_AK30  POWER  = PVDDCR_CPU0_P1
  AK31  VSS_AK31  POWER  = GND
  AK32  VDDCR_CPU0_AK32  POWER  = PVDDCR_CPU0_P1
  AK33  VDDCR_CPU0_AK33  POWER  = PVDDCR_CPU0_P1
  AK34  VSS_AK34  POWER  = GND
  AK35  \g3_rxn12||sata34_rxn\  IN  = GMI_CPU0_G1_CPU1_G3_TX_DN<3>
  AK36  \g3_rxp12||sata34_rxp\  IN  = GMI_CPU0_G1_CPU1_G3_TX_DP<3>
  AK37  VSS_AK37  POWER  = GND
  AK39  VSS_AK39  POWER  = GND
  AK40  G1_TXP3  OUT  = P5E_CPU1_G1_TX_DP<3>
  AK41  G1_TXN3  OUT  = P5E_CPU1_G1_TX_DN<3>
  AK42  VSS_AK42  POWER  = GND
  AK43  VDDCR_CPU0_AK43  POWER  = PVDDCR_CPU0_P1
  AK44  VDDCR_CPU0_AK44  POWER  = PVDDCR_CPU0_P1
  AK45  VSS_AK45  POWER  = GND
  AK46  VDDCR_CPU0_AK46  POWER  = PVDDCR_CPU0_P1
  AK47  VDDCR_CPU0_AK47  POWER  = PVDDCR_CPU0_P1
  AK48  VSS_AK48  POWER  = GND
  AK49  VDDCR_CPU0_AK49  POWER  = PVDDCR_CPU0_P1
  AK50  VDDCR_CPU0_AK50  POWER  = PVDDCR_CPU0_P1
  AK51  VSS_AK51  POWER  = GND
  AK52  VDDCR_CPU0_AK52  POWER  = PVDDCR_CPU0_P1
  AK53  VDDCR_CPU0_AK53  POWER  = PVDDCR_CPU0_P1
  AK54  VSS_AK54  POWER  = GND
  AK55  MCA_CHECK1  BI  = M_C_CPU1_SA_CB<1>
  AK56  MCA_CHECK2  BI  = M_C_CPU1_SA_CB<2>
  AK57  VSS_AK57  POWER  = GND
  AK58  MDA_CHECK1  BI  = M_D_CPU1_SA_CB<1>
  AK59  VSS_AK59  POWER  = GND
  AK60  MDA_CHECK2  BI  = M_D_CPU1_SA_CB<2>
  AK61  VSS_AK61  POWER  = GND
  AK62  MBA_CHECK1  BI  = M_B_CPU1_SA_CB<1>
  AK63  MBA_CHECK2  BI  = M_B_CPU1_SA_CB<2>
  AK64  VSS_AK64  POWER  = GND
  AK65  MFA_CHECK1  BI  = M_F_CPU1_SA_CB<1>
  AK66  VSS_AK66  POWER  = GND
  AK67  MFA_CHECK2  BI  = M_F_CPU1_SA_CB<2>
  AK68  VSS_AK68  POWER  = GND
  AK69  MEA_CHECK1  BI  = M_E_CPU1_SA_CB<1>
  AK70  MEA_CHECK2  BI  = M_E_CPU1_SA_CB<2>
  AK71  VSS_AK71  POWER  = GND
  AK72  MAA_CHECK1  BI  = M_A_CPU1_SA_CB<1>
  AK73  VSS_AK73  POWER  = GND
  AK74  MAA_CHECK2  BI  = M_A_CPU1_SA_CB<2>
  AL1  VSS_AL1  POWER  = GND
  AL2  MGA_DQS_H4  BI  = M_G_CPU1_SA_DQS_DP<4>
  AL3  MGA_CHECK3  BI  = M_G_CPU1_SA_CB<3>
  AL4  VSS_AL4  POWER  = GND
  AL5  MKA_DQS_H4  BI  = M_K_CPU1_SA_DQS_DP<4>
  AL6  VSS_AL6  POWER  = GND
  AL7  MKA_CHECK3  BI  = M_K_CPU1_SA_CB<3>
  AL8  VSS_AL8  POWER  = GND
  AL9  MLA_DQS_H4  BI  = M_L_CPU1_SA_DQS_DP<4>
  AL10  MLA_CHECK3  BI  = M_L_CPU1_SA_CB<3>
  AL11  VSS_AL11  POWER  = GND
  AL12  MHA_DQS_H4  BI  = M_H_CPU1_SA_DQS_DP<4>
  AL13  VSS_AL13  POWER  = GND
  AL14  MHA_CHECK3  BI  = M_H_CPU1_SA_CB<3>
  AL15  VSS_AL15  POWER  = GND
  AL16  MJA_DQS_H4  BI  = M_J_CPU1_SA_DQS_DP<4>
  AL17  MJA_CHECK3  BI  = M_J_CPU1_SA_CB<3>
  AL18  VSS_AL18  POWER  = GND
  AL19  MIA_DQS_H4  BI  = M_I_CPU1_SA_DQS_DP<4>
  AL20  VSS_AL20  POWER  = GND
  AL21  MIA_CHECK3  BI  = M_I_CPU1_SA_CB<3>
  AL22  VSS_AL22  POWER  = GND
  AL23  \g3_rxn0||sata20_rxn\  IN  = GMI_CPU0_G1_CPU1_G3_TX_DN<15>
  AL24  \g3_rxp0||sata20_rxp\  IN  = GMI_CPU0_G1_CPU1_G3_TX_DP<15>
  AL25  VSS_AL25  POWER  = GND
  AL26  \g3_rxn3||sata23_rxn\  IN  = GMI_CPU0_G1_CPU1_G3_TX_DN<12>
  AL27  \g3_rxp3||sata23_rxp\  IN  = GMI_CPU0_G1_CPU1_G3_TX_DP<12>
  AL28  VSS_AL28  POWER  = GND
  AL29  \g3_rxn6||sata26_rxn\  IN  = GMI_CPU0_G1_CPU1_G3_TX_DN<9>
  AL30  \g3_rxp6||sata26_rxp\  IN  = GMI_CPU0_G1_CPU1_G3_TX_DP<9>
  AL31  VSS_AL31  POWER  = GND
  AL32  \g3_rxn9||sata31_rxn\  IN  = GMI_CPU0_G1_CPU1_G3_TX_DN<6>
  AL33  \g3_rxp9||sata31_rxp\  IN  = GMI_CPU0_G1_CPU1_G3_TX_DP<6>
  AL34  VSS_AL34  POWER  = GND
  AL35  VDDCR_CPU0_AL35  POWER  = PVDDCR_CPU0_P1
  AL36  VDDCR_CPU0_AL36  POWER  = PVDDCR_CPU0_P1
  AL40  VDDCR_CPU0_AL40  POWER  = PVDDCR_CPU0_P1
  AL41  VDDCR_CPU0_AL41  POWER  = PVDDCR_CPU0_P1
  AL42  VSS_AL42  POWER  = GND
  AL43  G1_TXP6  OUT  = P5E_CPU1_G1_TX_DP<6>
  AL44  G1_TXN6  OUT  = P5E_CPU1_G1_TX_DN<6>
  AL45  VSS_AL45  POWER  = GND
  AL46  G1_TXP9  OUT  = P5E_CPU1_G1_TX_DP<9>
  AL47  G1_TXN9  OUT  = P5E_CPU1_G1_TX_DN<9>
  AL48  VSS_AL48  POWER  = GND
  AL49  G1_TXP12  OUT  = P5E_CPU1_G1_TX_DP<12>
  AL50  G1_TXN12  OUT  = P5E_CPU1_G1_TX_DN<12>
  AL51  VSS_AL51  POWER  = GND
  AL52  G1_TXP15  OUT  = P5E_CPU1_G1_TX_DP<15>
  AL53  G1_TXN15  OUT  = P5E_CPU1_G1_TX_DN<15>
  AL54  VSS_AL54  POWER  = GND
  AL55  MCA_CHECK3  BI  = M_C_CPU1_SA_CB<3>
  AL56  VSS_AL56  POWER  = GND
  AL57  MCA_DQS_H4  BI  = M_C_CPU1_SA_DQS_DP<4>
  AL58  VSS_AL58  POWER  = GND
  AL59  MDA_CHECK3  BI  = M_D_CPU1_SA_CB<3>
  AL60  MDA_DQS_H4  BI  = M_D_CPU1_SA_DQS_DP<4>
  AL61  VSS_AL61  POWER  = GND
  AL62  MBA_CHECK3  BI  = M_B_CPU1_SA_CB<3>
  AL63  VSS_AL63  POWER  = GND
  AL64  MBA_DQS_H4  BI  = M_B_CPU1_SA_DQS_DP<4>
  AL65  VSS_AL65  POWER  = GND
  AL66  MFA_CHECK3  BI  = M_F_CPU1_SA_CB<3>
  AL67  MFA_DQS_H4  BI  = M_F_CPU1_SA_DQS_DP<4>
  AL68  VSS_AL68  POWER  = GND
  AL69  MEA_CHECK3  BI  = M_E_CPU1_SA_CB<3>
  AL70  VSS_AL70  POWER  = GND
  AL71  MEA_DQS_H4  BI  = M_E_CPU1_SA_DQS_DP<4>
  AL72  VSS_AL72  POWER  = GND
  AL73  MAA_CHECK3  BI  = M_A_CPU1_SA_CB<3>
  AL74  MAA_DQS_H4  BI  = M_A_CPU1_SA_DQS_DP<4>
  AL75  VSS_AL75  POWER  = GND
  AM2  MGA_DQS_L4  BI  = M_G_CPU1_SA_DQS_DN<4>
  AM3  VSS_AM3  POWER  = GND
  AM4  MGA_DQS_L9  BI  = M_G_CPU1_SA_DQS_DN<9>
  AM5  VDDCR_SOC_AM5  POWER  = PVDDCR_SOC_P1
  AM6  MKA_DQS_L4  BI  = M_K_CPU1_SA_DQS_DN<4>
  AM7  MKA_DQS_L9  BI  = M_K_CPU1_SA_DQS_DN<9>
  AM8  VSS_AM8  POWER  = GND
  AM9  MLA_DQS_L4  BI  = M_L_CPU1_SA_DQS_DN<4>
  AM10  VSS_AM10  POWER  = GND
  AM11  MLA_DQS_L9  BI  = M_L_CPU1_SA_DQS_DN<9>
  AM12  VDDCR_SOC_AM12  POWER  = PVDDCR_SOC_P1
  AM13  MHA_DQS_L4  BI  = M_H_CPU1_SA_DQS_DN<4>
  AM14  MHA_DQS_L9  BI  = M_H_CPU1_SA_DQS_DN<9>
  AM15  VSS_AM15  POWER  = GND
  AM16  MJA_DQS_L4  BI  = M_J_CPU1_SA_DQS_DN<4>
  AM17  VSS_AM17  POWER  = GND
  AM18  MJA_DQS_L9  BI  = M_J_CPU1_SA_DQS_DN<9>
  AM19  VDDCR_SOC_AM19  POWER  = PVDDCR_SOC_P1
  AM20  MIA_DQS_L4  BI  = M_I_CPU1_SA_DQS_DN<4>
  AM21  MIA_DQS_L9  BI  = M_I_CPU1_SA_DQS_DN<9>
  AM22  VDDCR_SOC_AM22  POWER  = PVDDCR_SOC_P1
  AM23  VSS_AM23  POWER  = GND
  AM24  VSS_AM24  POWER  = GND
  AM25  VSS_AM25  POWER  = GND
  AM26  VSS_AM26  POWER  = GND
  AM27  VSS_AM27  POWER  = GND
  AM28  VSS_AM28  POWER  = GND
  AM29  VSS_AM29  POWER  = GND
  AM30  VSS_AM30  POWER  = GND
  AM31  VSS_AM31  POWER  = GND
  AM32  VSS_AM32  POWER  = GND
  AM33  VSS_AM33  POWER  = GND
  AM34  VSS_AM34  POWER  = GND
  AM35  \g3_rxn14||sata36_rxn\  IN  = GMI_CPU0_G1_CPU1_G3_TX_DN<1>
  AM36  \g3_rxp14||sata36_rxp\  IN  = GMI_CPU0_G1_CPU1_G3_TX_DP<1>
  AM37  VSS_AM37  POWER  = GND
  AM39  VSS_AM39  POWER  = GND
  AM40  G1_TXP1  OUT  = P5E_CPU1_G1_TX_DP<1>
  AM41  G1_TXN1  OUT  = P5E_CPU1_G1_TX_DN<1>
  AM42  VSS_AM42  POWER  = GND
  AM43  VSS_AM43  POWER  = GND
  AM44  VSS_AM44  POWER  = GND
  AM45  VSS_AM45  POWER  = GND
  AM46  VSS_AM46  POWER  = GND
  AM47  VSS_AM47  POWER  = GND
  AM48  VSS_AM48  POWER  = GND
  AM49  VSS_AM49  POWER  = GND
  AM50  VSS_AM50  POWER  = GND
  AM51  VSS_AM51  POWER  = GND
  AM52  VSS_AM52  POWER  = GND
  AM53  VSS_AM53  POWER  = GND
  AM54  VDDIO_AM54  POWER  = PVDDIO_P1
  AM55  MCA_DQS_L9  BI  = M_C_CPU1_SA_DQS_DN<9>
  AM56  MCA_DQS_L4  BI  = M_C_CPU1_SA_DQS_DN<4>
  AM57  VDDIO_AM57  POWER  = PVDDIO_P1
  AM58  MDA_DQS_L9  BI  = M_D_CPU1_SA_DQS_DN<9>
  AM59  VSS_AM59  POWER  = GND
  AM60  MDA_DQS_L4  BI  = M_D_CPU1_SA_DQS_DN<4>
  AM61  VSS_AM61  POWER  = GND
  AM62  MBA_DQS_L9  BI  = M_B_CPU1_SA_DQS_DN<9>
  AM63  MBA_DQS_L4  BI  = M_B_CPU1_SA_DQS_DN<4>
  AM64  VDDIO_AM64  POWER  = PVDDIO_P1
  AM65  MFA_DQS_L9  BI  = M_F_CPU1_SA_DQS_DN<9>
  AM66  VSS_AM66  POWER  = GND
  AM67  MFA_DQS_L4  BI  = M_F_CPU1_SA_DQS_DN<4>
  AM68  VSS_AM68  POWER  = GND
  AM69  MEA_DQS_L9  BI  = M_E_CPU1_SA_DQS_DN<9>
  AM70  MEA_DQS_L4  BI  = M_E_CPU1_SA_DQS_DN<4>
  AM71  VDDIO_AM71  POWER  = PVDDIO_P1
  AM72  MAA_DQS_L9  BI  = M_A_CPU1_SA_DQS_DN<9>
  AM73  VSS_AM73  POWER  = GND
  AM74  MAA_DQS_L4  BI  = M_A_CPU1_SA_DQS_DN<4>
  AN1  VSS_AN1  POWER  = GND
  AN2  MGA_CHECK4  BI  = M_G_CPU1_SA_CB<4>
  AN3  MGA_DQS_H9  BI  = M_G_CPU1_SA_DQS_DP<9>
  AN4  VSS_AN4  POWER  = GND
  AN5  MKA_CHECK4  BI  = M_K_CPU1_SA_CB<4>
  AN6  VSS_AN6  POWER  = GND
  AN7  MKA_DQS_H9  BI  = M_K_CPU1_SA_DQS_DP<9>
  AN8  VSS_AN8  POWER  = GND
  AN9  MLA_CHECK4  BI  = M_L_CPU1_SA_CB<4>
  AN10  MLA_DQS_H9  BI  = M_L_CPU1_SA_DQS_DP<9>
  AN11  VSS_AN11  POWER  = GND
  AN12  MHA_CHECK4  BI  = M_H_CPU1_SA_CB<4>
  AN13  VSS_AN13  POWER  = GND
  AN14  MHA_DQS_H9  BI  = M_H_CPU1_SA_DQS_DP<9>
  AN15  VSS_AN15  POWER  = GND
  AN16  MJA_CHECK4  BI  = M_J_CPU1_SA_CB<4>
  AN17  MJA_DQS_H9  BI  = M_J_CPU1_SA_DQS_DP<9>
  AN18  VSS_AN18  POWER  = GND
  AN19  MIA_CHECK4  BI  = M_I_CPU1_SA_CB<4>
  AN20  VSS_AN20  POWER  = GND
  AN21  MIA_DQS_H9  BI  = M_I_CPU1_SA_DQS_DP<9>
  AN22  VSS_AN22  POWER  = GND
  AN23  \g3_rxn2||sata22_rxn\  IN  = GMI_CPU0_G1_CPU1_G3_TX_DN<13>
  AN24  \g3_rxp2||sata22_rxp\  IN  = GMI_CPU0_G1_CPU1_G3_TX_DP<13>
  AN25  VSS_AN25  POWER  = GND
  AN26  \g3_rxn5||sata25_rxn\  IN  = GMI_CPU0_G1_CPU1_G3_TX_DN<10>
  AN27  \g3_rxp5||sata25_rxp\  IN  = GMI_CPU0_G1_CPU1_G3_TX_DP<10>
  AN28  VSS_AN28  POWER  = GND
  AN29  \g3_rxn8||sata30_rxn\  IN  = GMI_CPU0_G1_CPU1_G3_TX_DN<7>
  AN30  \g3_rxp8||sata30_rxp\  IN  = GMI_CPU0_G1_CPU1_G3_TX_DP<7>
  AN31  VSS_AN31  POWER  = GND
  AN32  \g3_rxn11||sata33_rxn\  IN  = GMI_CPU0_G1_CPU1_G3_TX_DN<4>
  AN33  \g3_rxp11||sata33_rxp\  IN  = GMI_CPU0_G1_CPU1_G3_TX_DP<4>
  AN34  VSS_AN34  POWER  = GND
  AN35  VSS_AN35  POWER  = GND
  AN36  VSS_AN36  POWER  = GND
  AN40  VSS_AN40  POWER  = GND
  AN41  VSS_AN41  POWER  = GND
  AN42  VSS_AN42  POWER  = GND
  AN43  G1_TXP4  OUT  = P5E_CPU1_G1_TX_DP<4>
  AN44  G1_TXN4  OUT  = P5E_CPU1_G1_TX_DN<4>
  AN45  VSS_AN45  POWER  = GND
  AN46  G1_TXP7  OUT  = P5E_CPU1_G1_TX_DP<7>
  AN47  G1_TXN7  OUT  = P5E_CPU1_G1_TX_DN<7>
  AN48  VSS_AN48  POWER  = GND
  AN49  G1_TXP10  OUT  = P5E_CPU1_G1_TX_DP<10>
  AN50  G1_TXN10  OUT  = P5E_CPU1_G1_TX_DN<10>
  AN51  VSS_AN51  POWER  = GND
  AN52  G1_TXP13  OUT  = P5E_CPU1_G1_TX_DP<13>
  AN53  G1_TXN13  OUT  = P5E_CPU1_G1_TX_DN<13>
  AN54  VSS_AN54  POWER  = GND
  AN55  MCA_DQS_H9  BI  = M_C_CPU1_SA_DQS_DP<9>
  AN56  VSS_AN56  POWER  = GND
  AN57  MCA_CHECK4  BI  = M_C_CPU1_SA_CB<4>
  AN58  VSS_AN58  POWER  = GND
  AN59  MDA_DQS_H9  BI  = M_D_CPU1_SA_DQS_DP<9>
  AN60  MDA_CHECK4  BI  = M_D_CPU1_SA_CB<4>
  AN61  VSS_AN61  POWER  = GND
  AN62  MBA_DQS_H9  BI  = M_B_CPU1_SA_DQS_DP<9>
  AN63  VSS_AN63  POWER  = GND
  AN64  MBA_CHECK4  BI  = M_B_CPU1_SA_CB<4>
  AN65  VSS_AN65  POWER  = GND
  AN66  MFA_DQS_H9  BI  = M_F_CPU1_SA_DQS_DP<9>
  AN67  MFA_CHECK4  BI  = M_F_CPU1_SA_CB<4>
  AN68  VSS_AN68  POWER  = GND
  AN69  MEA_DQS_H9  BI  = M_E_CPU1_SA_DQS_DP<9>
  AN70  VSS_AN70  POWER  = GND
  AN71  MEA_CHECK4  BI  = M_E_CPU1_SA_CB<4>
  AN72  VSS_AN72  POWER  = GND
  AN73  MAA_DQS_H9  BI  = M_A_CPU1_SA_DQS_DP<9>
  AN74  MAA_CHECK4  BI  = M_A_CPU1_SA_CB<4>
  AN75  VSS_AN75  POWER  = GND
  AP2  MGA_CHECK6  BI  = M_G_CPU1_SA_CB<6>
  AP3  VSS_AP3  POWER  = GND
  AP4  MGA_CHECK5  BI  = M_G_CPU1_SA_CB<5>
  AP5  VSS_AP5  POWER  = GND
  AP6  MKA_CHECK6  BI  = M_K_CPU1_SA_CB<6>
  AP7  MKA_CHECK5  BI  = M_K_CPU1_SA_CB<5>
  AP8  VSS_AP8  POWER  = GND
  AP9  MLA_CHECK6  BI  = M_L_CPU1_SA_CB<6>
  AP10  VSS_AP10  POWER  = GND
  AP11  MLA_CHECK5  BI  = M_L_CPU1_SA_CB<5>
  AP12  VSS_AP12  POWER  = GND
  AP13  MHA_CHECK6  BI  = M_H_CPU1_SA_CB<6>
  AP14  MHA_CHECK5  BI  = M_H_CPU1_SA_CB<5>
  AP15  VSS_AP15  POWER  = GND
  AP16  MJA_CHECK6  BI  = M_J_CPU1_SA_CB<6>
  AP17  VSS_AP17  POWER  = GND
